(kicad_pcb
	(version 20260206)
	(generator "pcbnew")
	(generator_version "10.0")
	(general
		(thickness 1.6)
		(legacy_teardrops no)
	)
	(paper "A4")
	(title_block
		(title "Wiwynn_Tioga_Pass_MB.brd")
		(comment 1 "Tioga Pass / footprints 2026-2030 of 4770")
	)
	(layers
		(0 "F.Cu" signal "TOP")
		(4 "In1.Cu" signal "L2GND")
		(6 "In2.Cu" signal "L3")
		(8 "In3.Cu" signal "L4GND")
		(10 "In4.Cu" signal "L5")
		(12 "In5.Cu" signal "L6GND")
		(14 "In6.Cu" signal "L7VCC")
		(16 "In7.Cu" signal "L8VCC")
		(18 "In8.Cu" signal "L9GND")
		(20 "In9.Cu" signal "L10")
		(22 "In10.Cu" signal "L11GND")
		(24 "In11.Cu" signal "L12")
		(26 "In12.Cu" signal "L13GND")
		(2 "B.Cu" signal "BOTTOM")
		(9 "F.Adhes" user "F.Adhesive")
		(11 "B.Adhes" user "B.Adhesive")
		(13 "F.Paste" user "Package Geometry/Pastemask Top")
		(15 "B.Paste" user "Package Geometry/Pastemask Bottom")
		(5 "F.SilkS" user "Ref Des/Silkscreen Top")
		(7 "B.SilkS" user "Ref Des/Silkscreen Bottom")
		(1 "F.Mask" user "Board Geometry/Soldermask Top")
		(3 "B.Mask" user "Board Geometry/Soldermask Bottom")
		(17 "Dwgs.User" user "User.Drawings")
		(19 "Cmts.User" user "User.Comments")
		(21 "Eco1.User" user "User.Eco1")
		(23 "Eco2.User" user "User.Eco2")
		(25 "Edge.Cuts" user "Board Geometry/Outline")
		(27 "Margin" user)
		(31 "F.CrtYd" user "Package Geometry/Place Bound Top")
		(29 "B.CrtYd" user "Package Geometry/Place Bound Bottom")
		(35 "F.Fab" user "Ref Des/Assembly Top")
		(33 "B.Fab" user "Ref Des/Assembly Bottom")
	)
	(footprint ""
		(layer "F.Cu")
		(at 259.452872 -77.636116)
		(property "Reference" "C5D25"
			(at 0 0 0)
			(layer "F.SilkS")
			(hide yes)
			(effects
				(font
					(size 1.27 1.27)
				)
			)
		)
		(property "Value" ""
			(at 0 0 0)
			(layer "F.Fab")
			(effects
				(font
					(size 1.27 1.27)
				)
			)
		)
		(duplicate_pad_numbers_are_jumpers no)
		(fp_poly
			(pts
				(xy -0.4953 -0.2032) (xy 0.4953 -0.2032) (xy 0.4953 1.6002) (xy -0.4953 1.6002)
			)
			(stroke
				(width 0)
				(type default)
			)
			(fill no)
			(layer "F.CrtYd")
		)
		(fp_line
			(start -0.4953 -0.2032)
			(end 0.4953 -0.2032)
			(stroke
				(width 0.1)
				(type default)
			)
			(layer "F.Fab")
		)
		(fp_line
			(start -0.4953 1.6002)
			(end -0.4953 -0.2032)
			(stroke
				(width 0.1)
				(type default)
			)
			(layer "F.Fab")
		)
		(fp_line
			(start 0.4953 -0.2032)
			(end 0.4953 1.6002)
			(stroke
				(width 0.1)
				(type default)
			)
			(layer "F.Fab")
		)
		(fp_line
			(start 0.4953 1.6002)
			(end -0.4953 1.6002)
			(stroke
				(width 0.1)
				(type default)
			)
			(layer "F.Fab")
		)
		(pad "1" smd rect
			(at 0 0)
			(size 0.762 0.889)
			(layers "F.Cu" "F.Mask" "F.Paste")
			(net "PVCCIN_CPU0")
		)
		(pad "2" smd rect
			(at 0 1.397)
			(size 0.762 0.889)
			(layers "F.Cu" "F.Mask" "F.Paste")
			(net "GND")
		)
		(zone
			(layer "F.Cu")
			(hatch none 0.5)
			(connect_pads
				(clearance 0)
			)
			(min_thickness 0.25)
			(keepout
				(tracks not_allowed)
				(vias allowed)
				(pads allowed)
				(copperpour not_allowed)
				(footprints allowed)
			)
			(placement
				(enabled no)
				(sheetname "")
			)
			(fill
				(thermal_gap 0.5)
				(thermal_bridge_width 0.5)
				(island_removal_mode 0)
			)
			(polygon
				(pts
					(xy 259.071872 -77.191616) (xy 259.833872 -77.191616) (xy 259.833872 -76.683616) (xy 259.071872 -76.683616)
				)
			)
		)
	)
	(footprint ""
		(layer "F.Cu")
		(at 387.8326 -65.3034)
		(property "Reference" "C22W8"
			(at 0 0 0)
			(layer "F.SilkS")
			(hide yes)
			(effects
				(font
					(size 1.27 1.27)
				)
			)
		)
		(property "Value" "*"
			(at -0.0762 -6.2357 0)
			(unlocked yes)
			(layer "F.Fab")
			(hide yes)
			(effects
				(font
					(size 1.27 1.016)
					(thickness 0.1524)
				)
			)
		)
		(property "Device Type" "SC22U16V5MX-4-GP_SMD-BCG5-SC22A"
			(at -0.0762 -8.2677 0)
			(unlocked yes)
			(layer "F.Fab")
			(hide yes)
			(effects
				(font
					(size 1.27 1.016)
					(thickness 0.1524)
				)
			)
		)
		(duplicate_pad_numbers_are_jumpers no)
		(fp_line
			(start 0.635 0)
			(end -0.635 0)
			(stroke
				(width 0.508)
				(type default)
			)
			(layer "F.SilkS")
		)
		(fp_rect
			(start -0.9652 1.778)
			(end 0.9652 -1.778)
			(stroke
				(width 0)
				(type default)
			)
			(fill no)
			(layer "F.CrtYd")
		)
		(fp_poly
			(pts
				(xy -0.9652 -1.778) (xy 0.9652 -1.778) (xy 0.9652 1.778) (xy -0.9652 1.778)
			)
			(stroke
				(width 0)
				(type default)
			)
			(fill no)
			(layer "F.Fab")
		)
		(pad "1" smd rect
			(at 0 -0.9652)
			(size 1.397 1.143)
			(layers "F.Cu" "F.Mask" "F.Paste")
			(net "VR_FET_SW_P5V_STBY_PVIN")
		)
		(pad "2" smd rect
			(at 0 0.9652)
			(size 1.397 1.143)
			(layers "F.Cu" "F.Mask" "F.Paste")
			(net "GND")
		)
	)
	(footprint ""
		(layer "F.Cu")
		(at 178.36261 -24.961088 90)
		(property "Reference" "R12W3"
			(at 0 0 90)
			(layer "F.SilkS")
			(hide yes)
			(effects
				(font
					(size 1.27 1.27)
				)
			)
		)
		(property "Value" "*"
			(at 0.064008 -4.108196 90)
			(unlocked yes)
			(layer "F.Fab")
			(hide yes)
			(effects
				(font
					(size 1.27 1.016)
					(thickness 0.1524)
				)
			)
		)
		(property "Device Type" "4D02R2F-GP_SMD-RG2-4D02R2F-GP,A"
			(at 0.064008 -5.632196 90)
			(unlocked yes)
			(layer "F.Fab")
			(hide yes)
			(effects
				(font
					(size 1.27 1.016)
					(thickness 0.1524)
				)
			)
		)
		(duplicate_pad_numbers_are_jumpers no)
		(fp_line
			(start 0.508 -0.9398)
			(end -0.508 -0.9398)
			(stroke
				(width 0.1524)
				(type default)
			)
			(layer "F.SilkS")
		)
		(fp_line
			(start -0.508 -0.9398)
			(end -0.508 0.9398)
			(stroke
				(width 0.1524)
				(type default)
			)
			(layer "F.SilkS")
		)
		(fp_rect
			(start -0.508 0.9398)
			(end 0.508 -0.9398)
			(stroke
				(width 0)
				(type default)
			)
			(fill no)
			(layer "F.CrtYd")
		)
		(fp_rect
			(start -0.508 0.9398)
			(end 0.508 -0.9398)
			(stroke
				(width 0)
				(type default)
			)
			(fill no)
			(layer "F.Fab")
		)
		(pad "1" smd custom
			(at 0 -0.4445 90)
			(size 0.1397 0.1397)
			(layers "F.Cu" "F.Mask" "F.Paste")
			(net "P12V_STBY")
			(options
				(clearance outline)
				(anchor circle)
			)
			(primitives
				(gr_poly
					(pts
						(arc
							(start -0.1778 -0.2794)
							(mid -0.249642 -0.249642)
							(end -0.2794 -0.1778)
						)
						(arc
							(start -0.2794 0.1778)
							(mid -0.249642 0.249642)
							(end -0.1778 0.2794)
						)
						(arc
							(start 0.1778 0.2794)
							(mid 0.249642 0.249642)
							(end 0.2794 0.1778)
						)
						(arc
							(start 0.2794 -0.1778)
							(mid 0.249642 -0.249642)
							(end 0.1778 -0.2794)
						)
					)
					(width 0)
					(fill yes)
				)
			)
		)
		(pad "2" smd custom
			(at 0 0.4445 90)
			(size 0.1397 0.1397)
			(layers "F.Cu" "F.Mask" "F.Paste")
			(net "P12V_NVDIMM_ABC_D")
			(options
				(clearance outline)
				(anchor circle)
			)
			(primitives
				(gr_poly
					(pts
						(arc
							(start -0.1778 -0.2794)
							(mid -0.249642 -0.249642)
							(end -0.2794 -0.1778)
						)
						(arc
							(start -0.2794 0.1778)
							(mid -0.249642 0.249642)
							(end -0.1778 0.2794)
						)
						(arc
							(start 0.1778 0.2794)
							(mid 0.249642 0.249642)
							(end 0.2794 0.1778)
						)
						(arc
							(start 0.2794 -0.1778)
							(mid 0.249642 -0.249642)
							(end 0.1778 -0.2794)
						)
					)
					(width 0)
					(fill yes)
				)
			)
		)
	)
	(footprint ""
		(layer "F.Cu")
		(at 5.602732 2.141474 90)
		(property "Reference" "RF20"
			(at -0.8382 -0.67818 90)
			(unlocked yes)
			(layer "F.SilkS")
			(effects
				(font
					(size 0.4064 0.254)
					(thickness 0.1524)
				)
				(justify left)
			)
		)
		(property "Value" ""
			(at 0 0 90)
			(layer "F.Fab")
			(effects
				(font
					(size 1.27 1.27)
				)
			)
		)
		(duplicate_pad_numbers_are_jumpers no)
		(fp_poly
			(pts
				(xy -0.2794 -0.1016) (xy 0.2794 -0.1016) (xy 0.2794 0.9906) (xy -0.2794 0.9906)
			)
			(stroke
				(width 0)
				(type default)
			)
			(fill no)
			(layer "F.CrtYd")
		)
		(fp_line
			(start 0.2794 -0.1016)
			(end -0.2794 -0.1016)
			(stroke
				(width 0.1)
				(type default)
			)
			(layer "F.Fab")
		)
		(fp_line
			(start -0.2794 -0.1016)
			(end -0.2794 0.9906)
			(stroke
				(width 0.1)
				(type default)
			)
			(layer "F.Fab")
		)
		(fp_line
			(start 0.2794 0.9906)
			(end 0.2794 -0.1016)
			(stroke
				(width 0.1)
				(type default)
			)
			(layer "F.Fab")
		)
		(fp_line
			(start -0.2794 0.9906)
			(end 0.2794 0.9906)
			(stroke
				(width 0.1)
				(type default)
			)
			(layer "F.Fab")
		)
		(pad "1" smd rect
			(at 0 0 90)
			(size 0.508 0.508)
			(layers "F.Cu" "F.Mask" "F.Paste")
			(net "VR_PVDDQ_GHJ_AIREF2")
		)
		(pad "2" smd rect
			(at 0 0.889 90)
			(size 0.508 0.508)
			(layers "F.Cu" "F.Mask" "F.Paste")
			(net "ISENSE_PVDDQ_GHJ_PH2_IMON")
		)
		(zone
			(layer "F.Cu")
			(hatch none 0.5)
			(connect_pads
				(clearance 0)
			)
			(min_thickness 0.25)
			(keepout
				(tracks allowed)
				(vias not_allowed)
				(pads allowed)
				(copperpour not_allowed)
				(footprints allowed)
			)
			(placement
				(enabled no)
				(sheetname "")
			)
			(fill
				(thermal_gap 0.5)
				(thermal_bridge_width 0.5)
				(island_removal_mode 0)
			)
			(polygon
				(pts
					(xy 5.856732 2.395474) (xy 5.856732 1.887474) (xy 6.237732 1.887474) (xy 6.237732 2.395474)
				)
			)
		)
		(zone
			(layer "F.Cu")
			(hatch none 0.5)
			(connect_pads
				(clearance 0)
			)
			(min_thickness 0.25)
			(keepout
				(tracks not_allowed)
				(vias allowed)
				(pads allowed)
				(copperpour not_allowed)
				(footprints allowed)
			)
			(placement
				(enabled no)
				(sheetname "")
			)
			(fill
				(thermal_gap 0.5)
				(thermal_bridge_width 0.5)
				(island_removal_mode 0)
			)
			(polygon
				(pts
					(xy 6.237732 2.395474) (xy 6.237732 1.887474) (xy 5.856732 1.887474) (xy 5.856732 2.395474)
				)
			)
		)
	)
	(footprint ""
		(layer "F.Cu")
		(at 33.278826 -85.7377 90)
		(property "Reference" "C1D33"
			(at 0 0 90)
			(layer "F.SilkS")
			(hide yes)
			(effects
				(font
					(size 1.27 1.27)
				)
			)
		)
		(property "Value" ""
			(at 0 0 90)
			(layer "F.Fab")
			(effects
				(font
					(size 1.27 1.27)
				)
			)
		)
		(duplicate_pad_numbers_are_jumpers no)
		(fp_rect
			(start 0.3048 0.9906)
			(end -0.3048 -0.1016)
			(stroke
				(width 0)
				(type default)
			)
			(fill no)
			(layer "F.CrtYd")
		)
		(fp_line
			(start 0.3048 -0.1016)
			(end -0.3048 -0.1016)
			(stroke
				(width 0.1)
				(type default)
			)
			(layer "F.Fab")
		)
		(fp_line
			(start -0.3048 -0.1016)
			(end -0.3048 0.9906)
			(stroke
				(width 0.1)
				(type default)
			)
			(layer "F.Fab")
		)
		(fp_line
			(start 0.3048 0.9906)
			(end 0.3048 -0.1016)
			(stroke
				(width 0.1)
				(type default)
			)
			(layer "F.Fab")
		)
		(fp_line
			(start -0.3048 0.9906)
			(end 0.3048 0.9906)
			(stroke
				(width 0.1)
				(type default)
			)
			(layer "F.Fab")
		)
		(pad "1" smd rect
			(at 0 0 90)
			(size 0.508 0.508)
			(layers "F.Cu" "F.Mask" "F.Paste")
			(net "P5V_STBY")
		)
		(pad "2" smd rect
			(at 0 0.889 90)
			(size 0.508 0.508)
			(layers "F.Cu" "F.Mask" "F.Paste")
			(net "GND")
		)
		(zone
			(layer "F.Cu")
			(hatch none 0.5)
			(connect_pads
				(clearance 0)
			)
			(min_thickness 0.25)
			(keepout
				(tracks not_allowed)
				(vias allowed)
				(pads allowed)
				(copperpour not_allowed)
				(footprints allowed)
			)
			(placement
				(enabled no)
				(sheetname "")
			)
			(fill
				(thermal_gap 0.5)
				(thermal_bridge_width 0.5)
				(island_removal_mode 0)
			)
			(polygon
				(pts
					(xy 33.913826 -85.9917) (xy 33.532826 -85.9917) (xy 33.532826 -85.4837) (xy 33.913826 -85.4837)
				)
			)
		)
		(zone
			(layer "F.Cu")
			(hatch none 0.5)
			(connect_pads
				(clearance 0)
			)
			(min_thickness 0.25)
			(keepout
				(tracks allowed)
				(vias not_allowed)
				(pads allowed)
				(copperpour not_allowed)
				(footprints allowed)
			)
			(placement
				(enabled no)
				(sheetname "")
			)
			(fill
				(thermal_gap 0.5)
				(thermal_bridge_width 0.5)
				(island_removal_mode 0)
			)
			(polygon
				(pts
					(xy 33.913826 -85.9917) (xy 33.532826 -85.9917) (xy 33.532826 -85.4837) (xy 33.913826 -85.4837)
				)
			)
		)
	)
)
